# S9S_MB_2U (Grand Teton) — schematic netlist excerpt (pin names and nets, part order shuffled) for the footprints in the layout excerpt that follows; sources: Cadence DE-HDL packaged netlist, KiCad conversion of 03242023_DA0F0TMBIJ0_F0T_Motherboard_J_brd_V01_OCP.brd

R2355  Q_RES  4.7K 5% EMPTY  pkg 0402LF  page 224 : A = P3V3_AUX ; B = FM_PS_EN_PLD_BUF1
C232  Q_CAP  10UF 6.3V 20% X6S  pkg C0402  page 77 : A = PVCCIN_CPU1 ; B = GND
C1577  Q_CAP_DIFFBUS  DIFF BUS_0.22UF 6.3V 20% X6S  pkg C0201  page 175 : \1\ = P5E_CPU0_PE4_TX_C_DP<1> ; \2\ = P5E_CPU0_PE4_TX_DP<1>

(kicad_pcb
	(version 20260206)
	(generator "pcbnew")
	(generator_version "10.0")
	(general
		(thickness 1.6)
		(legacy_teardrops no)
	)
	(paper "A4")
	(title_block
		(title "03242023_DA0F0TMBIJ0_F0T_Motherboard_J_brd_V01_OCP.brd")
		(comment 1 "Grand Teton / footprints 1573-1575 of 6105")
	)
	(layers
		(0 "F.Cu" signal "TOP")
		(4 "In1.Cu" signal "GND")
		(6 "In2.Cu" signal "IN1")
		(8 "In3.Cu" signal "GND1")
		(10 "In4.Cu" signal "IN2")
		(12 "In5.Cu" signal "GND2")
		(14 "In6.Cu" signal "IN3")
		(16 "In7.Cu" signal "GND3")
		(18 "In8.Cu" signal "VCC")
		(20 "In9.Cu" signal "VCC1")
		(22 "In10.Cu" signal "GND4")
		(24 "In11.Cu" signal "IN4")
		(26 "In12.Cu" signal "GND5")
		(28 "In13.Cu" signal "IN5")
		(30 "In14.Cu" signal "GND6")
		(32 "In15.Cu" signal "IN6")
		(34 "In16.Cu" signal "GND7")
		(2 "B.Cu" signal "BOTTOM")
		(9 "F.Adhes" user "F.Adhesive")
		(11 "B.Adhes" user "B.Adhesive")
		(13 "F.Paste" user "Package Geometry/Pastemask Top")
		(15 "B.Paste" user "Package Geometry/Pastemask Bottom")
		(5 "F.SilkS" user "Ref Des/Silkscreen Top")
		(7 "B.SilkS" user "Ref Des/Silkscreen Bottom")
		(1 "F.Mask" user "Board Geometry/Soldermask Top")
		(3 "B.Mask" user "Board Geometry/Soldermask Bottom")
		(17 "Dwgs.User" user "User.Drawings")
		(19 "Cmts.User" user "User.Comments")
		(21 "Eco1.User" user "User.Eco1")
		(23 "Eco2.User" user "User.Eco2")
		(25 "Edge.Cuts" user "Board Geometry/Outline")
		(27 "Margin" user)
		(31 "F.CrtYd" user "Package Geometry/Place Bound Top")
		(29 "B.CrtYd" user "Package Geometry/Place Bound Bottom")
		(35 "F.Fab" user "Ref Des/Assembly Top")
		(33 "B.Fab" user "Ref Des/Assembly Bottom")
	)
	(footprint ""
		(layer "F.Cu")
		(at 144.294606 -78.955138 180)
		(property "Reference" "R2355"
			(at 0 0 180)
			(layer "F.SilkS")
			(hide yes)
			(effects
				(font
					(size 1.27 1.27)
				)
			)
		)
		(property "Value" ""
			(at 0 0 180)
			(layer "F.Fab")
			(effects
				(font
					(size 1.27 1.27)
				)
			)
		)
		(duplicate_pad_numbers_are_jumpers no)
		(fp_line
			(start 0.7874 0.4064)
			(end -0.7874 0.4064)
			(stroke
				(width 0.1524)
				(type default)
			)
			(layer "F.SilkS")
		)
		(fp_line
			(start 0.7874 -0.4064)
			(end 0.7874 0.4064)
			(stroke
				(width 0.1524)
				(type default)
			)
			(layer "F.SilkS")
		)
		(fp_line
			(start -0.7874 0.4064)
			(end -0.7874 -0.4064)
			(stroke
				(width 0.1524)
				(type default)
			)
			(layer "F.SilkS")
		)
		(fp_line
			(start -0.7874 -0.4064)
			(end 0.7874 -0.4064)
			(stroke
				(width 0.1524)
				(type default)
			)
			(layer "F.SilkS")
		)
		(fp_line
			(start 0.67945 0.3048)
			(end 0.120396 0.3048)
			(stroke
				(width 0.1)
				(type default)
			)
			(layer "F.Fab")
		)
		(fp_line
			(start 0.67945 -0.3048)
			(end 0.67945 0.3048)
			(stroke
				(width 0.1)
				(type default)
			)
			(layer "F.Fab")
		)
		(fp_line
			(start 0.12065 -0.2794)
			(end 0.12065 -0.3048)
			(stroke
				(width 0.1)
				(type default)
			)
			(layer "F.Fab")
		)
		(fp_line
			(start 0.12065 -0.3048)
			(end 0.67945 -0.3048)
			(stroke
				(width 0.1)
				(type default)
			)
			(layer "F.Fab")
		)
		(fp_line
			(start 0.120396 0.3048)
			(end 0.120396 0.2794)
			(stroke
				(width 0.1)
				(type default)
			)
			(layer "F.Fab")
		)
		(fp_line
			(start 0.120396 0.2794)
			(end -0.12065 0.2794)
			(stroke
				(width 0.1)
				(type default)
			)
			(layer "F.Fab")
		)
		(fp_line
			(start -0.12065 0.3048)
			(end -0.67945 0.3048)
			(stroke
				(width 0.1)
				(type default)
			)
			(layer "F.Fab")
		)
		(fp_line
			(start -0.12065 0.2794)
			(end -0.12065 0.3048)
			(stroke
				(width 0.1)
				(type default)
			)
			(layer "F.Fab")
		)
		(fp_line
			(start -0.12065 -0.2794)
			(end 0.12065 -0.2794)
			(stroke
				(width 0.1)
				(type default)
			)
			(layer "F.Fab")
		)
		(fp_line
			(start -0.12065 -0.305054)
			(end -0.12065 -0.2794)
			(stroke
				(width 0.1)
				(type default)
			)
			(layer "F.Fab")
		)
		(fp_line
			(start -0.67945 0.3048)
			(end -0.67945 -0.305054)
			(stroke
				(width 0.1)
				(type default)
			)
			(layer "F.Fab")
		)
		(fp_line
			(start -0.67945 -0.305054)
			(end -0.12065 -0.305054)
			(stroke
				(width 0.1)
				(type default)
			)
			(layer "F.Fab")
		)
		(pad "1" smd circle
			(at -0.40005 0 180)
			(size 0 0)
			(layers "F.Cu" "F.Mask" "F.Paste")
			(net "P3V3_AUX")
		)
		(pad "2" smd circle
			(at 0.40005 0 180)
			(size 0 0)
			(layers "F.Cu" "F.Mask" "F.Paste")
			(net "FM_PS_EN_PLD_BUF1")
		)
	)
	(footprint ""
		(layer "F.Cu")
		(at 104.3432 -249.320558 -90)
		(property "Reference" "C232"
			(at 0 0 270)
			(layer "F.SilkS")
			(hide yes)
			(effects
				(font
					(size 1.27 1.27)
				)
			)
		)
		(property "Value" ""
			(at 0 0 270)
			(layer "F.Fab")
			(effects
				(font
					(size 1.27 1.27)
				)
			)
		)
		(duplicate_pad_numbers_are_jumpers no)
		(fp_line
			(start -0.7874 0.4064)
			(end -0.7874 -0.4064)
			(stroke
				(width 0.1524)
				(type default)
			)
			(layer "F.SilkS")
		)
		(fp_line
			(start 0.7874 0.4064)
			(end -0.7874 0.4064)
			(stroke
				(width 0.1524)
				(type default)
			)
			(layer "F.SilkS")
		)
		(fp_line
			(start -0.7874 -0.4064)
			(end 0.7874 -0.4064)
			(stroke
				(width 0.1524)
				(type default)
			)
			(layer "F.SilkS")
		)
		(fp_line
			(start 0.7874 -0.4064)
			(end 0.7874 0.4064)
			(stroke
				(width 0.1524)
				(type default)
			)
			(layer "F.SilkS")
		)
		(fp_line
			(start -0.67945 0.3048)
			(end -0.67945 -0.305054)
			(stroke
				(width 0.1)
				(type default)
			)
			(layer "F.Fab")
		)
		(fp_line
			(start -0.12065 0.3048)
			(end -0.67945 0.3048)
			(stroke
				(width 0.1)
				(type default)
			)
			(layer "F.Fab")
		)
		(fp_line
			(start 0.120396 0.3048)
			(end 0.120396 0.2794)
			(stroke
				(width 0.1)
				(type default)
			)
			(layer "F.Fab")
		)
		(fp_line
			(start 0.67945 0.3048)
			(end 0.120396 0.3048)
			(stroke
				(width 0.1)
				(type default)
			)
			(layer "F.Fab")
		)
		(fp_line
			(start -0.12065 0.2794)
			(end -0.12065 0.3048)
			(stroke
				(width 0.1)
				(type default)
			)
			(layer "F.Fab")
		)
		(fp_line
			(start 0.120396 0.2794)
			(end -0.12065 0.2794)
			(stroke
				(width 0.1)
				(type default)
			)
			(layer "F.Fab")
		)
		(fp_line
			(start -0.12065 -0.2794)
			(end 0.12065 -0.2794)
			(stroke
				(width 0.1)
				(type default)
			)
			(layer "F.Fab")
		)
		(fp_line
			(start 0.12065 -0.2794)
			(end 0.12065 -0.3048)
			(stroke
				(width 0.1)
				(type default)
			)
			(layer "F.Fab")
		)
		(fp_line
			(start 0.12065 -0.3048)
			(end 0.67945 -0.3048)
			(stroke
				(width 0.1)
				(type default)
			)
			(layer "F.Fab")
		)
		(fp_line
			(start 0.67945 -0.3048)
			(end 0.67945 0.3048)
			(stroke
				(width 0.1)
				(type default)
			)
			(layer "F.Fab")
		)
		(fp_line
			(start -0.67945 -0.305054)
			(end -0.12065 -0.305054)
			(stroke
				(width 0.1)
				(type default)
			)
			(layer "F.Fab")
		)
		(fp_line
			(start -0.12065 -0.305054)
			(end -0.12065 -0.2794)
			(stroke
				(width 0.1)
				(type default)
			)
			(layer "F.Fab")
		)
		(pad "1" smd circle
			(at -0.40005 0 270)
			(size 0 0)
			(layers "F.Cu" "F.Mask" "F.Paste")
			(net "PVCCIN_CPU1")
		)
		(pad "2" smd circle
			(at 0.40005 0 270)
			(size 0 0)
			(layers "F.Cu" "F.Mask" "F.Paste")
			(net "GND")
		)
	)
	(footprint ""
		(layer "F.Cu")
		(at 307.017928 -402.371052 -90)
		(property "Reference" "C1577"
			(at 0 0 270)
			(layer "F.SilkS")
			(hide yes)
			(effects
				(font
					(size 1.27 1.27)
				)
			)
		)
		(property "Value" ""
			(at 0 0 270)
			(layer "F.Fab")
			(effects
				(font
					(size 1.27 1.27)
				)
			)
		)
		(duplicate_pad_numbers_are_jumpers no)
		(fp_line
			(start -0.299974 0.150114)
			(end -0.299974 -0.150114)
			(stroke
				(width 0.1)
				(type default)
			)
			(layer "F.Fab")
		)
		(fp_line
			(start 0.299974 0.150114)
			(end -0.299974 0.150114)
			(stroke
				(width 0.1)
				(type default)
			)
			(layer "F.Fab")
		)
		(fp_line
			(start -0.299974 -0.150114)
			(end 0.299974 -0.150114)
			(stroke
				(width 0.1)
				(type default)
			)
			(layer "F.Fab")
		)
		(fp_line
			(start 0.299974 -0.150114)
			(end 0.299974 0.150114)
			(stroke
				(width 0.1)
				(type default)
			)
			(layer "F.Fab")
		)
		(pad "1" smd rect
			(at -0.2667 0 270)
			(size 0.3048 0.381)
			(layers "F.Cu" "F.Mask" "F.Paste")
			(net "P5E_CPU0_PE4_TX_C_DP<1>")
		)
		(pad "2" smd rect
			(at 0.2667 0 270)
			(size 0.3048 0.381)
			(layers "F.Cu" "F.Mask" "F.Paste")
			(net "P5E_CPU0_PE4_TX_DP<1>")
		)
	)
)
